# TIMECARD (Time Appliance Project (Time Card)) — schematic netlist excerpt (pin names and nets, part order shuffled) for the footprints in the layout excerpt that follows; sources: Cadence DE-HDL packaged netlist, KiCad conversion of R4006-B0001-02_R01.brd

TP134  TP_PIONT  pkg TP010CT020B030_PTH  page 25 : \1\ = IO_L21P_34
R66  RESISTOR  33OHM 1%  pkg SMC_0402R_H016  page 18 : \1\ = SHT3X_I2C_SDA ; \2\ = R_SHT3X_I2C_SDA
C260  CAPACITOR  10UF 25V 20%  pkg SMC_0805R_H057  page 29 : \1\ = VIN_XP1R0V ; \2\ = SG

(kicad_pcb
	(version 20260206)
	(generator "pcbnew")
	(generator_version "10.0")
	(general
		(thickness 1.6)
		(legacy_teardrops no)
	)
	(paper "A4")
	(title_block
		(title "timecard-production-celestica-r4006 — R4006-B0001-02_R01.brd")
		(comment 1 "Time Appliance Project (Time Card) / footprints 432-434 of 1113")
	)
	(layers
		(0 "F.Cu" signal "TOP")
		(4 "In1.Cu" signal "L02_GND1")
		(6 "In2.Cu" signal "L03_SIG1")
		(8 "In3.Cu" signal "L04_GND2")
		(10 "In4.Cu" signal "L05_VCC1")
		(12 "In5.Cu" signal "L06_VCC2")
		(14 "In6.Cu" signal "L07_GND3")
		(16 "In7.Cu" signal "L08_SIG2")
		(18 "In8.Cu" signal "L09_GND4")
		(2 "B.Cu" signal "BOTTOM")
		(9 "F.Adhes" user "F.Adhesive")
		(11 "B.Adhes" user "B.Adhesive")
		(13 "F.Paste" user "Package Geometry/Pastemask Top")
		(15 "B.Paste" user "Package Geometry/Pastemask Bottom")
		(5 "F.SilkS" user "Ref Des/Silkscreen Top")
		(7 "B.SilkS" user "Ref Des/Silkscreen Bottom")
		(1 "F.Mask" user "Board Geometry/Soldermask Top")
		(3 "B.Mask" user "Board Geometry/Soldermask Bottom")
		(17 "Dwgs.User" user "User.Drawings")
		(19 "Cmts.User" user "User.Comments")
		(21 "Eco1.User" user "User.Eco1")
		(23 "Eco2.User" user "User.Eco2")
		(25 "Edge.Cuts" user "Board Geometry/Outline")
		(27 "Margin" user)
		(31 "F.CrtYd" user "Package Geometry/Place Bound Top")
		(29 "B.CrtYd" user "Package Geometry/Place Bound Bottom")
		(35 "F.Fab" user "Ref Des/Assembly Top")
		(33 "B.Fab" user "Ref Des/Assembly Bottom")
	)
	(footprint ""
		(layer "F.Cu")
		(at 136.779 -53.086 -90)
		(property "Reference" "C260"
			(at 0 2.75463 90)
			(unlocked yes)
			(layer "F.SilkS")
			(effects
				(font
					(size 0.7874 0.5842)
					(thickness 0.1524)
				)
			)
		)
		(property "Value" "VAL*"
			(at 0.0762 3.134106 270)
			(unlocked yes)
			(layer "F.Fab")
			(hide yes)
			(effects
				(font
					(size 0.7874 0.5842)
					(thickness 0.1524)
				)
			)
		)
		(property "Tolerance" "TOL*"
			(at 0.0762 4.048506 270)
			(unlocked yes)
			(layer "Cmts.User")
			(hide yes)
			(effects
				(font
					(size 0.7874 0.5842)
					(thickness 0.1524)
				)
			)
		)
		(property "User Part Number" "PARTNUM*"
			(at 0.1016 5.013706 270)
			(unlocked yes)
			(layer "Cmts.User")
			(hide yes)
			(effects
				(font
					(size 0.7874 0.5842)
					(thickness 0.1524)
				)
			)
		)
		(property "Device Type" "CAPACITOR-G107-0F106-EM,10UF,2A"
			(at 0.0508 2.194306 270)
			(unlocked yes)
			(layer "F.Fab")
			(hide yes)
			(effects
				(font
					(size 0.7874 0.5842)
					(thickness 0.1524)
				)
			)
		)
		(duplicate_pad_numbers_are_jumpers no)
		(fp_line
			(start -1.5748 0.9398)
			(end 1.5748 0.9398)
			(stroke
				(width 0.1)
				(type default)
			)
			(layer "F.SilkS")
		)
		(fp_line
			(start 1.5748 0.9398)
			(end 1.5748 -0.9398)
			(stroke
				(width 0.1)
				(type default)
			)
			(layer "F.SilkS")
		)
		(fp_line
			(start -1.5748 -0.9398)
			(end -1.5748 0.9398)
			(stroke
				(width 0.1)
				(type default)
			)
			(layer "F.SilkS")
		)
		(fp_line
			(start 1.5748 -0.9398)
			(end -1.5748 -0.9398)
			(stroke
				(width 0.1)
				(type default)
			)
			(layer "F.SilkS")
		)
		(fp_rect
			(start 1.5748 0.9398)
			(end -1.5748 -0.9398)
			(stroke
				(width 0)
				(type default)
			)
			(fill no)
			(layer "F.CrtYd")
		)
		(fp_line
			(start -1.016 0.635)
			(end 1.016 0.635)
			(stroke
				(width 0.1)
				(type default)
			)
			(layer "F.Fab")
		)
		(fp_line
			(start 1.016 0.635)
			(end 1.016 -0.635)
			(stroke
				(width 0.1)
				(type default)
			)
			(layer "F.Fab")
		)
		(fp_line
			(start -1.016 -0.635)
			(end -1.016 0.635)
			(stroke
				(width 0.1)
				(type default)
			)
			(layer "F.Fab")
		)
		(fp_line
			(start 1.016 -0.635)
			(end -1.016 -0.635)
			(stroke
				(width 0.1)
				(type default)
			)
			(layer "F.Fab")
		)
		(pad "1" smd rect
			(at -0.8382 0 270)
			(size 0.9652 1.3716)
			(layers "F.Cu" "F.Mask" "F.Paste")
			(net "VIN_XP1R0V")
		)
		(pad "2" smd rect
			(at 0.8382 0 270)
			(size 0.9652 1.3716)
			(layers "F.Cu" "F.Mask" "F.Paste")
			(net "SG")
		)
		(zone
			(layer "F.Cu")
			(hatch none 0.5)
			(connect_pads
				(clearance 0)
			)
			(min_thickness 0.25)
			(keepout
				(tracks allowed)
				(vias not_allowed)
				(pads allowed)
				(copperpour not_allowed)
				(footprints allowed)
			)
			(placement
				(enabled no)
				(sheetname "")
			)
			(fill
				(thermal_gap 0.5)
				(thermal_bridge_width 0.5)
				(island_removal_mode 0)
			)
			(polygon
				(pts
					(xy 136.144 -52.8574) (xy 137.414 -52.8574) (xy 137.414 -53.3146) (xy 136.144 -53.3146)
				)
			)
		)
	)
	(footprint ""
		(layer "F.Cu")
		(at 127.762 -39.37 -90)
		(property "Reference" "TP134"
			(at 0.8128 -1.04775 90)
			(unlocked yes)
			(layer "F.SilkS")
			(effects
				(font
					(size 0.635 0.4064)
					(thickness 0.1524)
				)
				(justify left)
			)
		)
		(property "Value" ""
			(at 0 0 270)
			(layer "F.Fab")
			(effects
				(font
					(size 1.27 1.27)
				)
			)
		)
		(property "Device Type" "TP_PIONT-TP010CT020B030_PTH-TPA"
			(at -1.341882 0.996696 270)
			(unlocked yes)
			(layer "F.Fab")
			(hide yes)
			(effects
				(font
					(size 0.7874 0.5842)
					(thickness 0.1524)
				)
				(justify left)
			)
		)
		(duplicate_pad_numbers_are_jumpers no)
		(fp_poly
			(pts
				(arc
					(start 0 -0.889)
					(mid 0 0.889)
					(end 0 -0.889)
				)
			)
			(stroke
				(width 0)
				(type default)
			)
			(fill no)
			(layer "B.CrtYd")
		)
		(fp_poly
			(pts
				(arc
					(start 0 -0.889)
					(mid 0 0.889)
					(end 0 -0.889)
				)
			)
			(stroke
				(width 0)
				(type default)
			)
			(fill no)
			(layer "F.CrtYd")
		)
		(pad "1" thru_hole circle
			(at 0 0 270)
			(size 0.508 0.508)
			(drill 0.254)
			(layers "*.Cu" "*.Mask")
			(remove_unused_layers no)
			(net "IO_L21P_34")
			(clearance 0.1016)
			(padstack
				(mode front_inner_back)
				(layer "Inner"
					(shape circle)
					(size 0.508 0.508)
					(clearance 0.1016)
				)
				(layer "B.Cu"
					(shape circle)
					(size 0.762 0.762)
					(clearance -0.0254)
				)
			)
		)
	)
	(footprint ""
		(layer "F.Cu")
		(at 150.343108 -49.01311 90)
		(property "Reference" "R66"
			(at 0.00889 -3.237738 90)
			(unlocked yes)
			(layer "F.SilkS")
			(effects
				(font
					(size 0.7874 0.5842)
					(thickness 0.1524)
				)
			)
		)
		(property "Value" "VAL*"
			(at 0.02032 2.13233 90)
			(unlocked yes)
			(layer "F.Fab")
			(hide yes)
			(effects
				(font
					(size 0.7874 0.5842)
					(thickness 0.1524)
				)
			)
		)
		(property "Device Type" "RESISTOR-G155-133R0-01,33OHM,1%"
			(at 0.008382 1.210564 90)
			(unlocked yes)
			(layer "F.Fab")
			(hide yes)
			(effects
				(font
					(size 0.7874 0.5842)
					(thickness 0.1524)
				)
			)
		)
		(property "User Part Number" "PARTNUM*"
			(at 0.02032 4.024884 90)
			(unlocked yes)
			(layer "Cmts.User")
			(hide yes)
			(effects
				(font
					(size 0.7874 0.5842)
					(thickness 0.1524)
				)
			)
		)
		(property "Tolerance" "TOL*"
			(at 0.044704 3.05435 90)
			(unlocked yes)
			(layer "Cmts.User")
			(hide yes)
			(effects
				(font
					(size 0.7874 0.5842)
					(thickness 0.1524)
				)
			)
		)
		(duplicate_pad_numbers_are_jumpers no)
		(fp_line
			(start 1.143 -0.5588)
			(end -1.143 -0.5588)
			(stroke
				(width 0.1)
				(type default)
			)
			(layer "F.SilkS")
		)
		(fp_line
			(start -1.143 -0.5588)
			(end -1.143 0.5588)
			(stroke
				(width 0.1)
				(type default)
			)
			(layer "F.SilkS")
		)
		(fp_line
			(start 1.143 0.5588)
			(end 1.143 -0.5588)
			(stroke
				(width 0.1)
				(type default)
			)
			(layer "F.SilkS")
		)
		(fp_line
			(start -1.143 0.5588)
			(end 1.143 0.5588)
			(stroke
				(width 0.1)
				(type default)
			)
			(layer "F.SilkS")
		)
		(fp_rect
			(start 1.143 0.5588)
			(end -1.143 -0.5588)
			(stroke
				(width 0)
				(type default)
			)
			(fill no)
			(layer "F.CrtYd")
		)
		(fp_line
			(start 0.508 -0.3048)
			(end -0.508 -0.3048)
			(stroke
				(width 0.1)
				(type default)
			)
			(layer "F.Fab")
		)
		(fp_line
			(start -0.508 -0.3048)
			(end -0.508 0.3048)
			(stroke
				(width 0.1)
				(type default)
			)
			(layer "F.Fab")
		)
		(fp_line
			(start 0.508 0.3048)
			(end 0.508 -0.3048)
			(stroke
				(width 0.1)
				(type default)
			)
			(layer "F.Fab")
		)
		(fp_line
			(start -0.508 0.3048)
			(end 0.508 0.3048)
			(stroke
				(width 0.1)
				(type default)
			)
			(layer "F.Fab")
		)
		(pad "1" smd rect
			(at -0.5334 0 90)
			(size 0.7112 0.6096)
			(layers "F.Cu" "F.Mask" "F.Paste")
			(net "SHT3X_I2C_SDA")
		)
		(pad "2" smd rect
			(at 0.5334 0 90)
			(size 0.7112 0.6096)
			(layers "F.Cu" "F.Mask" "F.Paste")
			(net "R_SHT3X_I2C_SDA")
		)
		(zone
			(layer "F.Cu")
			(hatch none 0.5)
			(connect_pads
				(clearance 0)
			)
			(min_thickness 0.25)
			(keepout
				(tracks allowed)
				(vias not_allowed)
				(pads allowed)
				(copperpour not_allowed)
				(footprints allowed)
			)
			(placement
				(enabled no)
				(sheetname "")
			)
			(fill
				(thermal_gap 0.5)
				(thermal_bridge_width 0.5)
				(island_removal_mode 0)
			)
			(polygon
				(pts
					(xy 150.647908 -49.08931) (xy 150.038308 -49.08931) (xy 150.038308 -48.93691) (xy 150.647908 -48.93691)
				)
			)
		)
	)
)
